FILE_TYPE = CONNECTIVITY;
{Allegro Design Entry HDL 17.2-2016 S081 (4005846) 1/11/2022}
"PAGE_NUMBER" = 22;
0"NC";
1"GMI_CPU0_G0_CPU1_G2_TX_DN<15:0>";
2"GMI_CPU0_G0_CPU1_G2_TX_DP<15:0>";
3"GMI_CPU0_G1_CPU1_G3_TX_DP<15:0>";
4"GMI_CPU1_G2_CPU0_G0_TX_DN<15:0>";
5"GMI_CPU1_G2_CPU0_G0_TX_DP<15:0>";
6"GMI_CPU1_G3_CPU0_G1_TX_DP<15:0>";
7"GMI_CPU1_G3_CPU0_G1_TX_DN<15:0>";
8"GMI_CPU0_G1_CPU1_G3_TX_DN<15:0>";
9"GMI_CPU1_G2_CPU0_G0_TX_DP<7>";
10"GMI_CPU1_G3_CPU0_G1_TX_DN<7>";
11"GMI_CPU1_G3_CPU0_G1_TX_DN<6>";
12"GMI_CPU1_G3_CPU0_G1_TX_DN<5>";
13"GMI_CPU1_G3_CPU0_G1_TX_DP<7>";
14"GMI_CPU1_G3_CPU0_G1_TX_DN<4>";
15"GMI_CPU1_G3_CPU0_G1_TX_DP<6>";
16"GMI_CPU1_G3_CPU0_G1_TX_DN<3>";
17"GMI_CPU1_G3_CPU0_G1_TX_DP<5>";
18"GMI_CPU1_G3_CPU0_G1_TX_DN<2>";
19"GMI_CPU1_G3_CPU0_G1_TX_DP<4>";
20"GMI_CPU1_G3_CPU0_G1_TX_DN<1>";
21"GMI_CPU1_G3_CPU0_G1_TX_DP<3>";
22"GMI_CPU1_G3_CPU0_G1_TX_DN<0>";
23"GMI_CPU1_G3_CPU0_G1_TX_DP<2>";
24"GMI_CPU1_G3_CPU0_G1_TX_DP<1>";
25"GMI_CPU1_G3_CPU0_G1_TX_DP<0>";
26"GMI_CPU1_G3_CPU0_G1_TX_DN<8>";
27"GMI_CPU1_G3_CPU0_G1_TX_DN<9>";
28"GMI_CPU1_G3_CPU0_G1_TX_DN<10>";
29"GMI_CPU1_G3_CPU0_G1_TX_DN<11>";
30"GMI_CPU1_G3_CPU0_G1_TX_DN<12>";
31"GMI_CPU1_G3_CPU0_G1_TX_DN<13>";
32"GMI_CPU1_G3_CPU0_G1_TX_DN<14>";
33"GMI_CPU1_G3_CPU0_G1_TX_DN<15>";
34"GMI_CPU1_G3_CPU0_G1_TX_DP<8>";
35"GMI_CPU1_G3_CPU0_G1_TX_DP<9>";
36"GMI_CPU1_G3_CPU0_G1_TX_DP<10>";
37"GMI_CPU1_G3_CPU0_G1_TX_DP<11>";
38"GMI_CPU1_G3_CPU0_G1_TX_DP<12>";
39"GMI_CPU1_G3_CPU0_G1_TX_DP<13>";
40"GMI_CPU1_G3_CPU0_G1_TX_DP<14>";
41"GMI_CPU1_G3_CPU0_G1_TX_DP<15>";
42"GMI_CPU1_G2_CPU0_G0_TX_DP<15>";
43"GMI_CPU1_G2_CPU0_G0_TX_DP<14>";
44"GMI_CPU1_G2_CPU0_G0_TX_DP<13>";
45"GMI_CPU1_G2_CPU0_G0_TX_DP<12>";
46"GMI_CPU1_G2_CPU0_G0_TX_DP<11>";
47"GMI_CPU1_G2_CPU0_G0_TX_DP<10>";
48"GMI_CPU1_G2_CPU0_G0_TX_DP<9>";
49"GMI_CPU1_G2_CPU0_G0_TX_DP<8>";
50"GMI_CPU1_G2_CPU0_G0_TX_DP<6>";
51"GMI_CPU1_G2_CPU0_G0_TX_DP<5>";
52"GMI_CPU1_G2_CPU0_G0_TX_DP<4>";
53"GMI_CPU1_G2_CPU0_G0_TX_DP<3>";
54"GMI_CPU1_G2_CPU0_G0_TX_DP<2>";
55"GMI_CPU1_G2_CPU0_G0_TX_DP<1>";
56"GMI_CPU1_G2_CPU0_G0_TX_DP<0>";
57"GMI_CPU1_G2_CPU0_G0_TX_DN<15>";
58"GMI_CPU1_G2_CPU0_G0_TX_DN<14>";
59"GMI_CPU1_G2_CPU0_G0_TX_DN<13>";
60"GMI_CPU1_G2_CPU0_G0_TX_DN<12>";
61"GMI_CPU1_G2_CPU0_G0_TX_DN<11>";
62"GMI_CPU1_G2_CPU0_G0_TX_DN<10>";
63"GMI_CPU1_G2_CPU0_G0_TX_DN<9>";
64"GMI_CPU1_G2_CPU0_G0_TX_DN<8>";
65"GMI_CPU1_G2_CPU0_G0_TX_DN<7>";
66"GMI_CPU1_G2_CPU0_G0_TX_DN<6>";
67"GMI_CPU1_G2_CPU0_G0_TX_DN<5>";
68"GMI_CPU1_G2_CPU0_G0_TX_DN<4>";
69"GMI_CPU1_G2_CPU0_G0_TX_DN<3>";
70"GMI_CPU1_G2_CPU0_G0_TX_DN<2>";
71"GMI_CPU1_G2_CPU0_G0_TX_DN<1>";
72"GMI_CPU1_G2_CPU0_G0_TX_DN<0>";
73"GMI_CPU0_G1_CPU1_G3_TX_DP<15>";
74"GMI_CPU0_G1_CPU1_G3_TX_DP<10>";
75"GMI_CPU0_G1_CPU1_G3_TX_DP<11>";
76"GMI_CPU0_G1_CPU1_G3_TX_DP<12>";
77"GMI_CPU0_G1_CPU1_G3_TX_DP<13>";
78"GMI_CPU0_G1_CPU1_G3_TX_DP<14>";
79"GMI_CPU0_G1_CPU1_G3_TX_DN<9>";
80"GMI_CPU0_G1_CPU1_G3_TX_DN<10>";
81"GMI_CPU0_G1_CPU1_G3_TX_DN<11>";
82"GMI_CPU0_G1_CPU1_G3_TX_DN<12>";
83"GMI_CPU0_G1_CPU1_G3_TX_DN<13>";
84"GMI_CPU0_G1_CPU1_G3_TX_DN<14>";
85"GMI_CPU0_G1_CPU1_G3_TX_DN<15>";
86"GMI_CPU0_G1_CPU1_G3_TX_DP<7>";
87"GMI_CPU0_G1_CPU1_G3_TX_DP<6>";
88"GMI_CPU0_G1_CPU1_G3_TX_DP<5>";
89"GMI_CPU0_G1_CPU1_G3_TX_DP<4>";
90"GMI_CPU0_G1_CPU1_G3_TX_DP<8>";
91"GMI_CPU0_G1_CPU1_G3_TX_DP<9>";
92"GMI_CPU0_G1_CPU1_G3_TX_DP<3>";
93"GMI_CPU0_G1_CPU1_G3_TX_DP<2>";
94"GMI_CPU0_G1_CPU1_G3_TX_DP<1>";
95"GMI_CPU0_G1_CPU1_G3_TX_DP<0>";
96"GMI_CPU0_G1_CPU1_G3_TX_DN<7>";
97"GMI_CPU0_G1_CPU1_G3_TX_DN<6>";
98"GMI_CPU0_G1_CPU1_G3_TX_DN<5>";
99"GMI_CPU0_G1_CPU1_G3_TX_DN<4>";
100"GMI_CPU0_G1_CPU1_G3_TX_DN<3>";
101"GMI_CPU0_G1_CPU1_G3_TX_DN<2>";
102"GMI_CPU0_G1_CPU1_G3_TX_DN<1>";
103"GMI_CPU0_G1_CPU1_G3_TX_DN<0>";
104"GMI_CPU0_G1_CPU1_G3_TX_DN<8>";
105"GMI_CPU0_G0_CPU1_G2_TX_DP<15>";
106"GMI_CPU0_G0_CPU1_G2_TX_DP<14>";
107"GMI_CPU0_G0_CPU1_G2_TX_DP<13>";
108"GMI_CPU0_G0_CPU1_G2_TX_DP<12>";
109"GMI_CPU0_G0_CPU1_G2_TX_DP<11>";
110"GMI_CPU0_G0_CPU1_G2_TX_DP<10>";
111"GMI_CPU0_G0_CPU1_G2_TX_DP<9>";
112"GMI_CPU0_G0_CPU1_G2_TX_DP<8>";
113"GMI_CPU0_G0_CPU1_G2_TX_DP<7>";
114"GMI_CPU0_G0_CPU1_G2_TX_DP<6>";
115"GMI_CPU0_G0_CPU1_G2_TX_DP<5>";
116"GMI_CPU0_G0_CPU1_G2_TX_DP<4>";
117"GMI_CPU0_G0_CPU1_G2_TX_DP<3>";
118"GMI_CPU0_G0_CPU1_G2_TX_DP<2>";
119"GMI_CPU0_G0_CPU1_G2_TX_DP<1>";
120"GMI_CPU0_G0_CPU1_G2_TX_DP<0>";
121"GMI_CPU0_G0_CPU1_G2_TX_DN<15>";
122"GMI_CPU0_G0_CPU1_G2_TX_DN<14>";
123"GMI_CPU0_G0_CPU1_G2_TX_DN<13>";
124"GMI_CPU0_G0_CPU1_G2_TX_DN<12>";
125"GMI_CPU0_G0_CPU1_G2_TX_DN<11>";
126"GMI_CPU0_G0_CPU1_G2_TX_DN<10>";
127"GMI_CPU0_G0_CPU1_G2_TX_DN<9>";
128"GMI_CPU0_G0_CPU1_G2_TX_DN<8>";
129"GMI_CPU0_G0_CPU1_G2_TX_DN<7>";
130"GMI_CPU0_G0_CPU1_G2_TX_DN<6>";
131"GMI_CPU0_G0_CPU1_G2_TX_DN<5>";
132"GMI_CPU0_G0_CPU1_G2_TX_DN<4>";
133"GMI_CPU0_G0_CPU1_G2_TX_DN<3>";
134"GMI_CPU0_G0_CPU1_G2_TX_DN<2>";
135"GMI_CPU0_G0_CPU1_G2_TX_DN<1>";
136"GMI_CPU0_G0_CPU1_G2_TX_DN<0>";
%"GENOA_SP5"
"11","(-4775,4925)","0","pure_quanta","I207";
;
LOCATION"U25"
$SEC"11"
CDS_SEC"11"
PART_TYPE"SMLF"
MATERIAL"IO"
VALUE"SOCKET6096_13568-001"
PART_NUMBER"DGA^6000030"
CDS_LIB"pure_quanta"
NEEDS_NO_SIZE"TRUE"
CDS_LMAN_SYM_OUTLINE"-1100,950,1100,-950";
"G0_TXP15"
$PN"AE52"105;
"G0_TXP14"
$PN"AC52"106;
"G0_TXP13"
$PN"AG52"107;
"G0_TXP12"
$PN"AE49"108;
"G0_TXP11"
$PN"AC49"109;
"G0_TXP10"
$PN"AG49"110;
"G0_TXP9"
$PN"AE46"111;
"G0_TXP8"
$PN"AC46"112;
"G0_TXP7"
$PN"AG46"113;
"G0_TXP6"
$PN"AE43"114;
"G0_TXP5"
$PN"AC43"115;
"G0_TXP4"
$PN"AA43"116;
"G0_TXP3"
$PN"AG43"117;
"G0_TXP2"
$PN"AB40"118;
"G0_TXP1"
$PN"AD40"119;
"G0_TXP0"
$PN"AF40"120;
"G0_TXN15"
$PN"AE53"121;
"G0_TXN14"
$PN"AC53"122;
"G0_TXN13"
$PN"AG53"123;
"G0_TXN12"
$PN"AE50"124;
"G0_TXN11"
$PN"AC50"125;
"G0_TXN10"
$PN"AG50"126;
"G0_TXN9"
$PN"AE47"127;
"G0_TXN8"
$PN"AC47"128;
"G0_TXN7"
$PN"AG47"129;
"G0_TXN6"
$PN"AE44"130;
"G0_TXN5"
$PN"AC44"131;
"G0_TXN4"
$PN"AA44"132;
"G0_TXN3"
$PN"AG44"133;
"G0_TXN2"
$PN"AB41"134;
"G0_TXN1"
$PN"AD41"135;
"G0_TXN0"
$PN"AF41"136;
"G0_RXP15"
$PN"N53"42;
"G0_RXP14"
$PN"J53"43;
"G0_RXP13"
$PN"G53"44;
"G0_RXP12"
$PN"L53"45;
"G0_RXP11"
$PN"J50"46;
"G0_RXP10"
$PN"G50"47;
"G0_RXP9"
$PN"L50"48;
"G0_RXP8"
$PN"J47"49;
"G0_RXP7"
$PN"G47"9;
"G0_RXP6"
$PN"L47"50;
"G0_RXP5"
$PN"J44"51;
"G0_RXP4"
$PN"G44"52;
"G0_RXP3"
$PN"L44"53;
"G0_RXP2"
$PN"H41"54;
"G0_RXP1"
$PN"K41"55;
"G0_RXP0"
$PN"M41"56;
"G0_RXN15"
$PN"N52"57;
"G0_RXN14"
$PN"J52"58;
"G0_RXN13"
$PN"G52"59;
"G0_RXN12"
$PN"L52"60;
"G0_RXN11"
$PN"J49"61;
"G0_RXN10"
$PN"G49"62;
"G0_RXN9"
$PN"L49"63;
"G0_RXN8"
$PN"J46"64;
"G0_RXN7"
$PN"G46"65;
"G0_RXN6"
$PN"L46"66;
"G0_RXN5"
$PN"J43"67;
"G0_RXN4"
$PN"G43"68;
"G0_RXN3"
$PN"L43"69;
"G0_RXN2"
$PN"H40"70;
"G0_RXN1"
$PN"K40"71;
"G0_RXN0"
$PN"M40"72;
%"GENOA_SP5"
"12","(-4775,2200)","0","pure_quanta","I208";
;
LOCATION"U25"
$SEC"12"
CDS_SEC"12"
PART_TYPE"SMLF"
MATERIAL"IO"
VALUE"SOCKET6096_13568-001"
PART_NUMBER"DGA^6000030"
CDS_LIB"pure_quanta"
NEEDS_NO_SIZE"TRUE"
CDS_LMAN_SYM_OUTLINE"-1100,950,1100,-950";
"G1_RXN7"
$PN"N46"10;
"G1_RXN6"
$PN"U46"11;
"G1_RXN5"
$PN"R43"12;
"G1_RXP7"
$PN"N47"13;
"G1_TXN7"
$PN"AN47"96;
"G1_RXN4"
$PN"N43"14;
"G1_RXP6"
$PN"U47"15;
"G1_TXN6"
$PN"AL44"97;
"G1_RXN3"
$PN"U43"16;
"G1_RXP5"
$PN"R44"17;
"G1_TXN5"
$PN"AJ44"98;
"G1_TXP7"
$PN"AN46"86;
"G1_RXN2"
$PN"P40"18;
"G1_RXP4"
$PN"N44"19;
"G1_TXN4"
$PN"AN44"99;
"G1_TXP6"
$PN"AL43"87;
"G1_RXN1"
$PN"T40"20;
"G1_RXP3"
$PN"U44"21;
"G1_TXN3"
$PN"AK41"100;
"G1_TXP5"
$PN"AJ43"88;
"G1_RXN0"
$PN"V40"22;
"G1_RXP2"
$PN"P41"23;
"G1_TXN2"
$PN"AH41"101;
"G1_TXP4"
$PN"AN43"89;
"G1_RXP1"
$PN"T41"24;
"G1_TXN1"
$PN"AM41"102;
"G1_TXP3"
$PN"AK40"92;
"G1_RXP0"
$PN"V41"25;
"G1_TXN0"
$PN"AP41"103;
"G1_TXP2"
$PN"AH40"93;
"G1_TXP1"
$PN"AM40"94;
"G1_TXP0"
$PN"AP40"95;
"G1_RXN8"
$PN"R46"26;
"G1_RXN9"
$PN"W49"27;
"G1_RXN10"
$PN"N49"28;
"G1_RXN11"
$PN"R49"29;
"G1_RXN12"
$PN"U49"30;
"G1_RXN13"
$PN"W52"31;
"G1_RXN14"
$PN"R52"32;
"G1_RXN15"
$PN"U52"33;
"G1_RXP8"
$PN"R47"34;
"G1_RXP9"
$PN"W50"35;
"G1_RXP10"
$PN"N50"36;
"G1_RXP11"
$PN"R50"37;
"G1_RXP12"
$PN"U50"38;
"G1_RXP13"
$PN"W53"39;
"G1_RXP14"
$PN"R53"40;
"G1_RXP15"
$PN"U53"41;
"G1_TXN8"
$PN"AJ47"104;
"G1_TXN9"
$PN"AL47"79;
"G1_TXN10"
$PN"AN50"80;
"G1_TXN11"
$PN"AJ50"81;
"G1_TXN12"
$PN"AL50"82;
"G1_TXN13"
$PN"AN53"83;
"G1_TXN14"
$PN"AJ53"84;
"G1_TXN15"
$PN"AL53"85;
"G1_TXP8"
$PN"AJ46"90;
"G1_TXP9"
$PN"AL46"91;
"G1_TXP10"
$PN"AN49"74;
"G1_TXP11"
$PN"AJ49"75;
"G1_TXP12"
$PN"AL49"76;
"G1_TXP13"
$PN"AN52"77;
"G1_TXP14"
$PN"AJ52"78;
"G1_TXP15"
$PN"AL52"73;
%"TAP"
"6","(-3100,5675)","2","mstr_standard","I245";
;
BOM_COST"IO_SLOT"
CDS_LIB"mstr_standard"
BODY_TYPE"PLUMBING"
HDL_TAP"TRUE"
ROOM"RISER1";
"B \NAC \NWC"2;
"S \NAC"
BN"0"120;
%"TAP"
"6","(-2950,5625)","2","mstr_standard","I246";
;
BOM_COST"IO_SLOT"
CDS_LIB"mstr_standard"
BODY_TYPE"PLUMBING"
HDL_TAP"TRUE"
ROOM"RISER1";
"B \NAC \NWC"1;
"S \NAC"
BN"0"136;
%"TAP"
"6","(-2950,5525)","2","mstr_standard","I247";
;
BOM_COST"IO_SLOT"
CDS_LIB"mstr_standard"
BODY_TYPE"PLUMBING"
HDL_TAP"TRUE"
ROOM"RISER1";
"B \NAC \NWC"1;
"S \NAC"
BN"1"135;
%"TAP"
"6","(-2950,5425)","2","standard","I248";
;
CDS_LIB"standard"
BOM_COST"IO_SLOT"
BODY_TYPE"PLUMBING"
HDL_TAP"TRUE"
ROOM"RISER1";
"B \NAC \NWC"1;
"S \NAC"
BN"2"134;
%"TAP"
"6","(-3100,5475)","2","standard","I249";
;
CDS_LIB"standard"
BOM_COST"IO_SLOT"
BODY_TYPE"PLUMBING"
HDL_TAP"TRUE"
ROOM"RISER1";
"B \NAC \NWC"2;
"S \NAC"
BN"2"118;
%"TAP"
"6","(-3100,5575)","2","mstr_standard","I250";
;
CDS_LIB"mstr_standard"
BOM_COST"IO_SLOT"
BODY_TYPE"PLUMBING"
HDL_TAP"TRUE"
ROOM"RISER1";
"B \NAC \NWC"2;
"S \NAC"
BN"1"119;
%"TAP"
"6","(-2950,5325)","2","standard","I251";
;
CDS_LIB"standard"
BOM_COST"IO_SLOT"
BODY_TYPE"PLUMBING"
HDL_TAP"TRUE"
ROOM"RISER1";
"B \NAC \NWC"1;
"S \NAC"
BN"3"133;
%"TAP"
"6","(-2950,5225)","2","standard","I252";
;
CDS_LIB"standard"
BOM_COST"IO_SLOT"
BODY_TYPE"PLUMBING"
HDL_TAP"TRUE"
ROOM"RISER1";
"B \NAC \NWC"1;
"S \NAC"
BN"4"132;
%"TAP"
"6","(-2950,5125)","2","standard","I253";
;
CDS_LIB"standard"
BOM_COST"IO_SLOT"
BODY_TYPE"PLUMBING"
HDL_TAP"TRUE"
ROOM"RISER1";
"B \NAC \NWC"1;
"S \NAC"
BN"5"131;
%"TAP"
"6","(-3100,5275)","2","standard","I254";
;
BOM_COST"IO_SLOT"
CDS_LIB"standard"
BODY_TYPE"PLUMBING"
HDL_TAP"TRUE"
ROOM"RISER1";
"B \NAC \NWC"2;
"S \NAC"
BN"4"116;
%"TAP"
"6","(-3100,5175)","2","standard","I255";
;
BOM_COST"IO_SLOT"
CDS_LIB"standard"
BODY_TYPE"PLUMBING"
HDL_TAP"TRUE"
ROOM"RISER1";
"B \NAC \NWC"2;
"S \NAC"
BN"5"115;
%"TAP"
"6","(-3100,5375)","2","standard","I256";
;
BOM_COST"IO_SLOT"
CDS_LIB"standard"
BODY_TYPE"PLUMBING"
HDL_TAP"TRUE"
ROOM"RISER1";
"B \NAC \NWC"2;
"S \NAC"
BN"3"117;
%"TAP"
"6","(-2950,5025)","2","standard","I257";
;
CDS_LIB"standard"
BOM_COST"IO_SLOT"
BODY_TYPE"PLUMBING"
HDL_TAP"TRUE"
ROOM"RISER1";
"B \NAC \NWC"1;
"S \NAC"
BN"6"130;
%"TAP"
"6","(-2950,4925)","2","standard","I258";
;
CDS_LIB"standard"
BOM_COST"IO_SLOT"
BODY_TYPE"PLUMBING"
HDL_TAP"TRUE"
ROOM"RISER1";
"B \NAC \NWC"1;
"S \NAC"
BN"7"129;
%"TAP"
"6","(-3100,4875)","2","standard","I259";
;
BOM_COST"IO_SLOT"
CDS_LIB"standard"
BODY_TYPE"PLUMBING"
HDL_TAP"TRUE"
ROOM"RISER1";
"B \NAC \NWC"2;
"S \NAC"
BN"8"112;
%"TAP"
"6","(-3100,4975)","2","standard","I260";
;
BOM_COST"IO_SLOT"
CDS_LIB"standard"
BODY_TYPE"PLUMBING"
HDL_TAP"TRUE"
ROOM"RISER1";
"B \NAC \NWC"2;
"S \NAC"
BN"7"113;
%"TAP"
"6","(-3100,5075)","2","standard","I261";
;
BOM_COST"IO_SLOT"
CDS_LIB"standard"
BODY_TYPE"PLUMBING"
HDL_TAP"TRUE"
ROOM"RISER1";
"B \NAC \NWC"2;
"S \NAC"
BN"6"114;
%"TAP"
"6","(-2950,4825)","2","standard","I262";
;
CDS_LIB"standard"
BOM_COST"IO_SLOT"
BODY_TYPE"PLUMBING"
HDL_TAP"TRUE"
ROOM"RISER1";
"B \NAC \NWC"1;
"S \NAC"
BN"8"128;
%"TAP"
"6","(-2950,4725)","2","standard","I263";
;
CDS_LIB"standard"
BOM_COST"IO_SLOT"
BODY_TYPE"PLUMBING"
HDL_TAP"TRUE"
ROOM"RISER1";
"B \NAC \NWC"1;
"S \NAC"
BN"9"127;
%"TAP"
"6","(-2950,4625)","2","standard","I264";
;
CDS_LIB"standard"
BOM_COST"IO_SLOT"
BODY_TYPE"PLUMBING"
HDL_TAP"TRUE"
ROOM"RISER1";
"B \NAC \NWC"1;
"S \NAC"
BN"10"126;
%"TAP"
"6","(-3100,4675)","2","standard","I265";
;
BOM_COST"IO_SLOT"
CDS_LIB"standard"
BODY_TYPE"PLUMBING"
HDL_TAP"TRUE"
ROOM"RISER1";
"B \NAC \NWC"2;
"S \NAC"
BN"10"110;
%"TAP"
"6","(-3100,4775)","2","standard","I266";
;
BOM_COST"IO_SLOT"
CDS_LIB"standard"
BODY_TYPE"PLUMBING"
HDL_TAP"TRUE"
ROOM"RISER1";
"B \NAC \NWC"2;
"S \NAC"
BN"9"111;
%"TAP"
"6","(-2950,4525)","2","standard","I267";
;
CDS_LIB"standard"
BOM_COST"IO_SLOT"
BODY_TYPE"PLUMBING"
HDL_TAP"TRUE"
ROOM"RISER1";
"B \NAC \NWC"1;
"S \NAC"
BN"11"125;
%"TAP"
"6","(-2950,4425)","2","standard","I268";
;
CDS_LIB"standard"
BOM_COST"IO_SLOT"
BODY_TYPE"PLUMBING"
HDL_TAP"TRUE"
ROOM"RISER1";
"B \NAC \NWC"1;
"S \NAC"
BN"12"124;
%"TAP"
"6","(-3100,4375)","2","standard","I269";
;
BOM_COST"IO_SLOT"
CDS_LIB"standard"
BODY_TYPE"PLUMBING"
HDL_TAP"TRUE"
ROOM"RISER1";
"B \NAC \NWC"2;
"S \NAC"
BN"13"107;
%"TAP"
"6","(-3100,4475)","2","standard","I270";
;
BOM_COST"IO_SLOT"
CDS_LIB"standard"
BODY_TYPE"PLUMBING"
HDL_TAP"TRUE"
ROOM"RISER1";
"B \NAC \NWC"2;
"S \NAC"
BN"12"108;
%"TAP"
"6","(-3100,4575)","2","standard","I271";
;
BOM_COST"IO_SLOT"
CDS_LIB"standard"
BODY_TYPE"PLUMBING"
HDL_TAP"TRUE"
ROOM"RISER1";
"B \NAC \NWC"2;
"S \NAC"
BN"11"109;
%"TAP"
"6","(-2950,4225)","2","standard","I272";
;
BOM_COST"IO_SLOT"
CDS_LIB"standard"
BODY_TYPE"PLUMBING"
HDL_TAP"TRUE"
ROOM"RISER1";
"B \NAC \NWC"1;
"S \NAC"
BN"14"122;
%"TAP"
"6","(-2950,4125)","2","standard","I273";
;
CDS_LIB"standard"
BOM_COST"IO_SLOT"
BODY_TYPE"PLUMBING"
HDL_TAP"TRUE"
ROOM"RISER1";
"B \NAC \NWC"1;
"S \NAC"
BN"15"121;
%"TAP"
"6","(-2950,4325)","2","standard","I274";
;
CDS_LIB"standard"
BOM_COST"IO_SLOT"
BODY_TYPE"PLUMBING"
HDL_TAP"TRUE"
ROOM"RISER1";
"B \NAC \NWC"1;
"S \NAC"
BN"13"123;
%"TAP"
"6","(-3100,4175)","2","standard","I275";
;
BOM_COST"IO_SLOT"
CDS_LIB"standard"
BODY_TYPE"PLUMBING"
HDL_TAP"TRUE"
ROOM"RISER1";
"B \NAC \NWC"2;
"S \NAC"
BN"15"105;
%"TAP"
"6","(-3100,4275)","2","standard","I276";
;
BOM_COST"IO_SLOT"
CDS_LIB"standard"
BODY_TYPE"PLUMBING"
HDL_TAP"TRUE"
ROOM"RISER1";
"B \NAC \NWC"2;
"S \NAC"
BN"14"106;
%"TAP"
"6","(-6525,5675)","0","mstr_standard","I277";
;
CDS_LIB"mstr_standard"
BODY_TYPE"PLUMBING"
HDL_TAP"TRUE";
"B \NAC \NWC"5;
"S \NAC"
BN"0"56;
%"TAP"
"6","(-6525,5575)","0","mstr_standard","I278";
;
CDS_LIB"mstr_standard"
BODY_TYPE"PLUMBING"
HDL_TAP"TRUE";
"B \NAC \NWC"5;
"S \NAC"
BN"1"55;
%"TAP"
"6","(-6525,5475)","0","mstr_standard","I279";
;
CDS_LIB"mstr_standard"
BODY_TYPE"PLUMBING"
HDL_TAP"TRUE";
"B \NAC \NWC"5;
"S \NAC"
BN"2"54;
%"TAP"
"6","(-6675,5625)","0","mstr_standard","I280";
;
CDS_LIB"mstr_standard"
BODY_TYPE"PLUMBING"
HDL_TAP"TRUE";
"B \NAC \NWC"4;
"S \NAC"
BN"0"72;
%"TAP"
"6","(-6675,5525)","0","mstr_standard","I281";
;
CDS_LIB"mstr_standard"
BODY_TYPE"PLUMBING"
HDL_TAP"TRUE";
"B \NAC \NWC"4;
"S \NAC"
BN"1"71;
%"TAP"
"6","(-6675,5425)","0","standard","I282";
;
CDS_LIB"standard"
BODY_TYPE"PLUMBING"
HDL_TAP"TRUE";
"B \NAC \NWC"4;
"S \NAC"
BN"2"70;
%"TAP"
"6","(-6525,5275)","0","standard","I283";
;
CDS_LIB"standard"
BODY_TYPE"PLUMBING"
HDL_TAP"TRUE";
"B \NAC \NWC"5;
"S \NAC"
BN"4"52;
%"TAP"
"6","(-6525,5375)","0","standard","I284";
;
CDS_LIB"standard"
BODY_TYPE"PLUMBING"
HDL_TAP"TRUE";
"B \NAC \NWC"5;
"S \NAC"
BN"3"53;
%"TAP"
"6","(-6525,5175)","0","standard","I285";
;
CDS_LIB"standard"
BODY_TYPE"PLUMBING"
HDL_TAP"TRUE";
"B \NAC \NWC"5;
"S \NAC"
BN"5"51;
%"TAP"
"6","(-6675,5325)","0","standard","I286";
;
CDS_LIB"standard"
BODY_TYPE"PLUMBING"
HDL_TAP"TRUE";
"B \NAC \NWC"4;
"S \NAC"
BN"3"69;
%"TAP"
"6","(-6675,5225)","0","standard","I287";
;
CDS_LIB"standard"
BODY_TYPE"PLUMBING"
HDL_TAP"TRUE";
"B \NAC \NWC"4;
"S \NAC"
BN"4"68;
%"TAP"
"6","(-6675,5125)","0","standard","I288";
;
CDS_LIB"standard"
BODY_TYPE"PLUMBING"
HDL_TAP"TRUE";
"B \NAC \NWC"4;
"S \NAC"
BN"5"67;
%"TAP"
"6","(-6525,5075)","0","standard","I289";
;
CDS_LIB"standard"
BODY_TYPE"PLUMBING"
HDL_TAP"TRUE";
"B \NAC \NWC"5;
"S \NAC"
BN"6"50;
%"TAP"
"6","(-6525,4975)","0","standard","I290";
;
CDS_LIB"standard"
BODY_TYPE"PLUMBING"
HDL_TAP"TRUE";
"B \NAC \NWC"5;
"S \NAC"
BN"7"9;
%"TAP"
"6","(-6525,4875)","0","standard","I291";
;
CDS_LIB"standard"
BODY_TYPE"PLUMBING"
HDL_TAP"TRUE";
"B \NAC \NWC"5;
"S \NAC"
BN"8"49;
%"TAP"
"6","(-6675,5025)","0","standard","I292";
;
CDS_LIB"standard"
BODY_TYPE"PLUMBING"
HDL_TAP"TRUE";
"B \NAC \NWC"4;
"S \NAC"
BN"6"66;
%"TAP"
"6","(-6675,4925)","0","standard","I293";
;
CDS_LIB"standard"
BODY_TYPE"PLUMBING"
HDL_TAP"TRUE";
"B \NAC \NWC"4;
"S \NAC"
BN"7"65;
%"TAP"
"6","(-6525,4775)","0","standard","I294";
;
CDS_LIB"standard"
BODY_TYPE"PLUMBING"
HDL_TAP"TRUE";
"B \NAC \NWC"5;
"S \NAC"
BN"9"48;
%"TAP"
"6","(-6525,4675)","0","standard","I295";
;
CDS_LIB"standard"
BODY_TYPE"PLUMBING"
HDL_TAP"TRUE";
"B \NAC \NWC"5;
"S \NAC"
BN"10"47;
%"TAP"
"6","(-6675,4825)","0","standard","I296";
;
CDS_LIB"standard"
BODY_TYPE"PLUMBING"
HDL_TAP"TRUE";
"B \NAC \NWC"4;
"S \NAC"
BN"8"64;
%"TAP"
"6","(-6675,4725)","0","standard","I297";
;
CDS_LIB"standard"
BODY_TYPE"PLUMBING"
HDL_TAP"TRUE";
"B \NAC \NWC"4;
"S \NAC"
BN"9"63;
%"TAP"
"6","(-6675,4625)","0","standard","I298";
;
CDS_LIB"standard"
BODY_TYPE"PLUMBING"
HDL_TAP"TRUE";
"B \NAC \NWC"4;
"S \NAC"
BN"10"62;
%"TAP"
"6","(-6525,4575)","0","standard","I299";
;
CDS_LIB"standard"
BODY_TYPE"PLUMBING"
HDL_TAP"TRUE";
"B \NAC \NWC"5;
"S \NAC"
BN"11"46;
%"TAP"
"6","(-6525,4475)","0","standard","I300";
;
CDS_LIB"standard"
BODY_TYPE"PLUMBING"
HDL_TAP"TRUE";
"B \NAC \NWC"5;
"S \NAC"
BN"12"45;
%"TAP"
"6","(-6525,4375)","0","standard","I301";
;
CDS_LIB"standard"
BODY_TYPE"PLUMBING"
HDL_TAP"TRUE";
"B \NAC \NWC"5;
"S \NAC"
BN"13"44;
%"TAP"
"6","(-6675,4525)","0","standard","I302";
;
CDS_LIB"standard"
BODY_TYPE"PLUMBING"
HDL_TAP"TRUE";
"B \NAC \NWC"4;
"S \NAC"
BN"11"61;
%"TAP"
"6","(-6675,4425)","0","standard","I303";
;
CDS_LIB"standard"
BODY_TYPE"PLUMBING"
HDL_TAP"TRUE";
"B \NAC \NWC"4;
"S \NAC"
BN"12"60;
%"TAP"
"6","(-6525,4275)","0","standard","I304";
;
CDS_LIB"standard"
BODY_TYPE"PLUMBING"
HDL_TAP"TRUE";
"B \NAC \NWC"5;
"S \NAC"
BN"14"43;
%"TAP"
"6","(-6525,4175)","0","standard","I305";
;
CDS_LIB"standard"
BODY_TYPE"PLUMBING"
HDL_TAP"TRUE";
"B \NAC \NWC"5;
"S \NAC"
BN"15"42;
%"TAP"
"6","(-6675,4325)","0","standard","I306";
;
CDS_LIB"standard"
BODY_TYPE"PLUMBING"
HDL_TAP"TRUE";
"B \NAC \NWC"4;
"S \NAC"
BN"13"59;
%"TAP"
"6","(-6675,4225)","0","standard","I307";
;
CDS_LIB"standard"
BODY_TYPE"PLUMBING"
HDL_TAP"TRUE";
"B \NAC \NWC"4;
"S \NAC"
BN"14"58;
%"TAP"
"6","(-6675,4125)","0","standard","I308";
;
CDS_LIB"standard"
BODY_TYPE"PLUMBING"
HDL_TAP"TRUE";
"B \NAC \NWC"4;
"S \NAC"
BN"15"57;
%"TAP"
"6","(-2950,2900)","2","mstr_standard","I313";
;
CDS_LIB"mstr_standard"
BOM_COST"IO_SLOT"
BODY_TYPE"PLUMBING"
HDL_TAP"TRUE"
ROOM"RISER1";
"B \NAC \NWC"8;
"S \NAC"
BN"0"103;
%"TAP"
"6","(-3100,2850)","2","mstr_standard","I314";
;
CDS_LIB"mstr_standard"
BOM_COST"IO_SLOT"
BODY_TYPE"PLUMBING"
HDL_TAP"TRUE"
ROOM"RISER1";
"B \NAC \NWC"3;
"S \NAC"
BN"1"94;
%"TAP"
"6","(-3100,2950)","2","mstr_standard","I315";
;
BOM_COST"IO_SLOT"
CDS_LIB"mstr_standard"
BODY_TYPE"PLUMBING"
HDL_TAP"TRUE"
ROOM"RISER1";
"B \NAC \NWC"3;
"S \NAC"
BN"0"95;
%"TAP"
"6","(-2950,2800)","2","mstr_standard","I316";
;
BOM_COST"IO_SLOT"
CDS_LIB"mstr_standard"
BODY_TYPE"PLUMBING"
HDL_TAP"TRUE"
ROOM"RISER1";
"B \NAC \NWC"8;
"S \NAC"
BN"1"102;
%"TAP"
"6","(-2950,2700)","2","standard","I317";
;
BOM_COST"IO_SLOT"
CDS_LIB"standard"
BODY_TYPE"PLUMBING"
HDL_TAP"TRUE"
ROOM"RISER1";
"B \NAC \NWC"8;
"S \NAC"
BN"2"101;
%"TAP"
"6","(-2950,2600)","2","standard","I318";
;
BOM_COST"IO_SLOT"
CDS_LIB"standard"
BODY_TYPE"PLUMBING"
HDL_TAP"TRUE"
ROOM"RISER1";
"B \NAC \NWC"8;
"S \NAC"
BN"3"100;
%"TAP"
"6","(-3100,2650)","2","standard","I319";
;
CDS_LIB"standard"
BOM_COST"IO_SLOT"
BODY_TYPE"PLUMBING"
HDL_TAP"TRUE"
ROOM"RISER1";
"B \NAC \NWC"3;
"S \NAC"
BN"3"92;
%"TAP"
"6","(-3100,2750)","2","standard","I320";
;
CDS_LIB"standard"
BOM_COST"IO_SLOT"
BODY_TYPE"PLUMBING"
HDL_TAP"TRUE"
ROOM"RISER1";
"B \NAC \NWC"3;
"S \NAC"
BN"2"93;
%"TAP"
"6","(-2950,2400)","2","standard","I321";
;
BOM_COST"IO_SLOT"
CDS_LIB"standard"
BODY_TYPE"PLUMBING"
HDL_TAP"TRUE"
ROOM"RISER1";
"B \NAC \NWC"8;
"S \NAC"
BN"5"98;
%"TAP"
"6","(-2950,2500)","2","standard","I322";
;
BOM_COST"IO_SLOT"
CDS_LIB"standard"
BODY_TYPE"PLUMBING"
HDL_TAP"TRUE"
ROOM"RISER1";
"B \NAC \NWC"8;
"S \NAC"
BN"4"99;
%"TAP"
"6","(-3100,2350)","2","standard","I323";
;
CDS_LIB"standard"
BOM_COST"IO_SLOT"
BODY_TYPE"PLUMBING"
HDL_TAP"TRUE"
ROOM"RISER1";
"B \NAC \NWC"3;
"S \NAC"
BN"6"87;
%"TAP"
"6","(-3100,2450)","2","standard","I324";
;
CDS_LIB"standard"
BOM_COST"IO_SLOT"
BODY_TYPE"PLUMBING"
HDL_TAP"TRUE"
ROOM"RISER1";
"B \NAC \NWC"3;
"S \NAC"
BN"5"88;
%"TAP"
"6","(-3100,2550)","2","standard","I325";
;
CDS_LIB"standard"
BOM_COST"IO_SLOT"
BODY_TYPE"PLUMBING"
HDL_TAP"TRUE"
ROOM"RISER1";
"B \NAC \NWC"3;
"S \NAC"
BN"4"89;
%"TAP"
"6","(-2950,2200)","2","standard","I326";
;
BOM_COST"IO_SLOT"
CDS_LIB"standard"
BODY_TYPE"PLUMBING"
HDL_TAP"TRUE"
ROOM"RISER1";
"B \NAC \NWC"8;
"S \NAC"
BN"7"96;
%"TAP"
"6","(-2950,2300)","2","standard","I327";
;
BOM_COST"IO_SLOT"
CDS_LIB"standard"
BODY_TYPE"PLUMBING"
HDL_TAP"TRUE"
ROOM"RISER1";
"B \NAC \NWC"8;
"S \NAC"
BN"6"97;
%"TAP"
"6","(-2950,2100)","2","standard","I328";
;
BOM_COST"IO_SLOT"
CDS_LIB"standard"
BODY_TYPE"PLUMBING"
HDL_TAP"TRUE"
ROOM"RISER1";
"B \NAC \NWC"8;
"S \NAC"
BN"8"104;
%"TAP"
"6","(-3100,2150)","2","standard","I329";
;
CDS_LIB"standard"
BOM_COST"IO_SLOT"
BODY_TYPE"PLUMBING"
HDL_TAP"TRUE"
ROOM"RISER1";
"B \NAC \NWC"3;
"S \NAC"
BN"8"90;
%"TAP"
"6","(-3100,2050)","2","standard","I330";
;
CDS_LIB"standard"
BOM_COST"IO_SLOT"
BODY_TYPE"PLUMBING"
HDL_TAP"TRUE"
ROOM"RISER1";
"B \NAC \NWC"3;
"S \NAC"
BN"9"91;
%"TAP"
"6","(-3100,2250)","2","standard","I331";
;
CDS_LIB"standard"
BOM_COST"IO_SLOT"
BODY_TYPE"PLUMBING"
HDL_TAP"TRUE"
ROOM"RISER1";
"B \NAC \NWC"3;
"S \NAC"
BN"7"86;
%"TAP"
"6","(-2950,2000)","2","standard","I332";
;
BOM_COST"IO_SLOT"
CDS_LIB"standard"
BODY_TYPE"PLUMBING"
HDL_TAP"TRUE"
ROOM"RISER1";
"B \NAC \NWC"8;
"S \NAC"
BN"9"79;
%"TAP"
"6","(-2950,1900)","2","standard","I333";
;
BOM_COST"IO_SLOT"
CDS_LIB"standard"
BODY_TYPE"PLUMBING"
HDL_TAP"TRUE"
ROOM"RISER1";
"B \NAC \NWC"8;
"S \NAC"
BN"10"80;
%"TAP"
"6","(-2950,1800)","2","standard","I334";
;
BOM_COST"IO_SLOT"
CDS_LIB"standard"
BODY_TYPE"PLUMBING"
HDL_TAP"TRUE"
ROOM"RISER1";
"B \NAC \NWC"8;
"S \NAC"
BN"11"81;
%"TAP"
"6","(-3100,1850)","2","standard","I335";
;
CDS_LIB"standard"
BOM_COST"IO_SLOT"
BODY_TYPE"PLUMBING"
HDL_TAP"TRUE"
ROOM"RISER1";
"B \NAC \NWC"3;
"S \NAC"
BN"11"75;
%"TAP"
"6","(-3100,1950)","2","standard","I336";
;
CDS_LIB"standard"
BOM_COST"IO_SLOT"
BODY_TYPE"PLUMBING"
HDL_TAP"TRUE"
ROOM"RISER1";
"B \NAC \NWC"3;
"S \NAC"
BN"10"74;
%"TAP"
"6","(-2950,1700)","2","standard","I337";
;
BOM_COST"IO_SLOT"
CDS_LIB"standard"
BODY_TYPE"PLUMBING"
HDL_TAP"TRUE"
ROOM"RISER1";
"B \NAC \NWC"8;
"S \NAC"
BN"12"82;
%"TAP"
"6","(-2950,1600)","2","standard","I338";
;
BOM_COST"IO_SLOT"
CDS_LIB"standard"
BODY_TYPE"PLUMBING"
HDL_TAP"TRUE"
ROOM"RISER1";
"B \NAC \NWC"8;
"S \NAC"
BN"13"83;
%"TAP"
"6","(-3100,1550)","2","standard","I339";
;
CDS_LIB"standard"
BOM_COST"IO_SLOT"
BODY_TYPE"PLUMBING"
HDL_TAP"TRUE"
ROOM"RISER1";
"B \NAC \NWC"3;
"S \NAC"
BN"14"78;
%"TAP"
"6","(-3100,1650)","2","standard","I340";
;
CDS_LIB"standard"
BOM_COST"IO_SLOT"
BODY_TYPE"PLUMBING"
HDL_TAP"TRUE"
ROOM"RISER1";
"B \NAC \NWC"3;
"S \NAC"
BN"13"77;
%"TAP"
"6","(-3100,1750)","2","standard","I341";
;
CDS_LIB"standard"
BOM_COST"IO_SLOT"
BODY_TYPE"PLUMBING"
HDL_TAP"TRUE"
ROOM"RISER1";
"B \NAC \NWC"3;
"S \NAC"
BN"12"76;
%"TAP"
"6","(-2950,1400)","2","standard","I342";
;
BOM_COST"IO_SLOT"
CDS_LIB"standard"
BODY_TYPE"PLUMBING"
HDL_TAP"TRUE"
ROOM"RISER1";
"B \NAC \NWC"8;
"S \NAC"
BN"15"85;
%"TAP"
"6","(-2950,1500)","2","standard","I343";
;
BOM_COST"IO_SLOT"
CDS_LIB"standard"
BODY_TYPE"PLUMBING"
HDL_TAP"TRUE"
ROOM"RISER1";
"B \NAC \NWC"8;
"S \NAC"
BN"14"84;
%"TAP"
"6","(-3100,1450)","2","standard","I344";
;
CDS_LIB"standard"
BOM_COST"IO_SLOT"
BODY_TYPE"PLUMBING"
HDL_TAP"TRUE"
ROOM"RISER1";
"B \NAC \NWC"3;
"S \NAC"
BN"15"73;
%"TAP"
"6","(-6525,2950)","0","mstr_standard","I345";
;
CDS_LIB"mstr_standard"
BODY_TYPE"PLUMBING"
HDL_TAP"TRUE";
"B \NAC \NWC"6;
"S \NAC"
BN"0"25;
%"TAP"
"6","(-6525,2850)","0","mstr_standard","I346";
;
CDS_LIB"mstr_standard"
BODY_TYPE"PLUMBING"
HDL_TAP"TRUE";
"B \NAC \NWC"6;
"S \NAC"
BN"1"24;
%"TAP"
"6","(-6675,2900)","0","mstr_standard","I347";
;
CDS_LIB"mstr_standard"
BODY_TYPE"PLUMBING"
HDL_TAP"TRUE";
"B \NAC \NWC"7;
"S \NAC"
BN"0"22;
%"TAP"
"6","(-6525,2750)","0","mstr_standard","I348";
;
CDS_LIB"mstr_standard"
BODY_TYPE"PLUMBING"
HDL_TAP"TRUE";
"B \NAC \NWC"6;
"S \NAC"
BN"2"23;
%"TAP"
"6","(-6525,2650)","0","standard","I349";
;
CDS_LIB"standard"
BODY_TYPE"PLUMBING"
HDL_TAP"TRUE";
"B \NAC \NWC"6;
"S \NAC"
BN"3"21;
%"TAP"
"6","(-6675,2700)","0","standard","I350";
;
CDS_LIB"standard"
BODY_TYPE"PLUMBING"
HDL_TAP"TRUE";
"B \NAC \NWC"7;
"S \NAC"
BN"2"18;
%"TAP"
"6","(-6675,2800)","0","mstr_standard","I351";
;
CDS_LIB"mstr_standard"
BODY_TYPE"PLUMBING"
HDL_TAP"TRUE";
"B \NAC \NWC"7;
"S \NAC"
BN"1"20;
%"TAP"
"6","(-6675,2600)","0","standard","I352";
;
CDS_LIB"standard"
BODY_TYPE"PLUMBING"
HDL_TAP"TRUE";
"B \NAC \NWC"7;
"S \NAC"
BN"3"16;
%"TAP"
"6","(-6525,2550)","0","standard","I353";
;
CDS_LIB"standard"
BODY_TYPE"PLUMBING"
HDL_TAP"TRUE";
"B \NAC \NWC"6;
"S \NAC"
BN"4"19;
%"TAP"
"6","(-6525,2450)","0","standard","I354";
;
CDS_LIB"standard"
BODY_TYPE"PLUMBING"
HDL_TAP"TRUE";
"B \NAC \NWC"6;
"S \NAC"
BN"5"17;
%"TAP"
"6","(-6525,2350)","0","standard","I355";
;
CDS_LIB"standard"
BODY_TYPE"PLUMBING"
HDL_TAP"TRUE";
"B \NAC \NWC"6;
"S \NAC"
BN"6"15;
%"TAP"
"6","(-6675,2500)","0","standard","I356";
;
CDS_LIB"standard"
BODY_TYPE"PLUMBING"
HDL_TAP"TRUE";
"B \NAC \NWC"7;
"S \NAC"
BN"4"14;
%"TAP"
"6","(-6675,2400)","0","standard","I357";
;
CDS_LIB"standard"
BODY_TYPE"PLUMBING"
HDL_TAP"TRUE";
"B \NAC \NWC"7;
"S \NAC"
BN"5"12;
%"TAP"
"6","(-6525,2250)","0","standard","I358";
;
CDS_LIB"standard"
BODY_TYPE"PLUMBING"
HDL_TAP"TRUE";
"B \NAC \NWC"6;
"S \NAC"
BN"7"13;
%"TAP"
"6","(-6525,2150)","0","standard","I359";
;
CDS_LIB"standard"
BODY_TYPE"PLUMBING"
HDL_TAP"TRUE";
"B \NAC \NWC"6;
"S \NAC"
BN"8"34;
%"TAP"
"6","(-6525,2050)","0","standard","I360";
;
CDS_LIB"standard"
BODY_TYPE"PLUMBING"
HDL_TAP"TRUE";
"B \NAC \NWC"6;
"S \NAC"
BN"9"35;
%"TAP"
"6","(-6675,2200)","0","standard","I361";
;
CDS_LIB"standard"
BODY_TYPE"PLUMBING"
HDL_TAP"TRUE";
"B \NAC \NWC"7;
"S \NAC"
BN"7"10;
%"TAP"
"6","(-6675,2300)","0","standard","I362";
;
CDS_LIB"standard"
BODY_TYPE"PLUMBING"
HDL_TAP"TRUE";
"B \NAC \NWC"7;
"S \NAC"
BN"6"11;
%"TAP"
"6","(-6675,2100)","0","standard","I363";
;
CDS_LIB"standard"
BODY_TYPE"PLUMBING"
HDL_TAP"TRUE";
"B \NAC \NWC"7;
"S \NAC"
BN"8"26;
%"TAP"
"6","(-6525,1950)","0","standard","I366";
;
CDS_LIB"standard"
BODY_TYPE"PLUMBING"
HDL_TAP"TRUE";
"B \NAC \NWC"6;
"S \NAC"
BN"10"36;
%"TAP"
"6","(-6525,1850)","0","standard","I367";
;
CDS_LIB"standard"
BODY_TYPE"PLUMBING"
HDL_TAP"TRUE";
"B \NAC \NWC"6;
"S \NAC"
BN"11"37;
%"TAP"
"6","(-6675,2000)","0","standard","I368";
;
CDS_LIB"standard"
BODY_TYPE"PLUMBING"
HDL_TAP"TRUE";
"B \NAC \NWC"7;
"S \NAC"
BN"9"27;
%"TAP"
"6","(-6675,1900)","0","standard","I369";
;
CDS_LIB"standard"
BODY_TYPE"PLUMBING"
HDL_TAP"TRUE";
"B \NAC \NWC"7;
"S \NAC"
BN"10"28;
%"TAP"
"6","(-6675,1800)","0","standard","I370";
;
CDS_LIB"standard"
BODY_TYPE"PLUMBING"
HDL_TAP"TRUE";
"B \NAC \NWC"7;
"S \NAC"
BN"11"29;
%"TAP"
"6","(-6525,1750)","0","standard","I371";
;
CDS_LIB"standard"
BODY_TYPE"PLUMBING"
HDL_TAP"TRUE";
"B \NAC \NWC"6;
"S \NAC"
BN"12"38;
%"TAP"
"6","(-6525,1650)","0","standard","I372";
;
CDS_LIB"standard"
BODY_TYPE"PLUMBING"
HDL_TAP"TRUE";
"B \NAC \NWC"6;
"S \NAC"
BN"13"39;
%"TAP"
"6","(-6525,1550)","0","standard","I373";
;
CDS_LIB"standard"
BODY_TYPE"PLUMBING"
HDL_TAP"TRUE";
"B \NAC \NWC"6;
"S \NAC"
BN"14"40;
%"TAP"
"6","(-6675,1700)","0","standard","I374";
;
CDS_LIB"standard"
BODY_TYPE"PLUMBING"
HDL_TAP"TRUE";
"B \NAC \NWC"7;
"S \NAC"
BN"12"30;
%"TAP"
"6","(-6675,1600)","0","standard","I375";
;
CDS_LIB"standard"
BODY_TYPE"PLUMBING"
HDL_TAP"TRUE";
"B \NAC \NWC"7;
"S \NAC"
BN"13"31;
%"TAP"
"6","(-6525,1450)","0","standard","I376";
;
CDS_LIB"standard"
BODY_TYPE"PLUMBING"
HDL_TAP"TRUE";
"B \NAC \NWC"6;
"S \NAC"
BN"15"41;
%"TAP"
"6","(-6675,1400)","0","standard","I377";
;
CDS_LIB"standard"
BODY_TYPE"PLUMBING"
HDL_TAP"TRUE";
"B \NAC \NWC"7;
"S \NAC"
BN"15"33;
%"TAP"
"6","(-6675,1500)","0","standard","I378";
;
CDS_LIB"standard"
BODY_TYPE"PLUMBING"
HDL_TAP"TRUE";
"B \NAC \NWC"7;
"S \NAC"
BN"14"32;
END.
